# ZAIUS-LBB-EVT2-X01-BOM-X03-20161116.xls — POP_GA (bom)
| FOXCONN TECHNOLOGY GROUP |  |  |  |  |  |  |  |  |  |  |  |  |
| BILL OF MATERIAL |  |  |  |  |  |  |  |  |  |  |  |  |
| REV OF  BOM |  | CUSTOMER | DELL |  | CUSTOMER P/N |  | PRODUCT CODE |  | PWA  REV |  | DATE |  |
| Sourcing (Single/Sole/Multi) | Critical Commodity (Y or N) | Component Class (1, 2, other) | Dell PSL (Y or N) | Item Number | Foxconn P/N | Dell P/N | Part Description | Manufacturer  Full Name | Manufacturer  Part Number | Qty | RoHS Status | Location |
